(kicad_pcb
	(version 20260206)
	(generator "pcbnew")
	(generator_version "10.0")
	(general
		(thickness 1.6)
		(legacy_teardrops no)
	)
	(paper "A4")
	(title_block
		(title "01162023_DA0F0TEBIF0_F0T_Expander_BD_F_brd_V02_OCP.brd")
		(comment 1 "Grand Teton / footprints 7137-7146 of 9728")
	)
	(layers
		(0 "F.Cu" signal "TOP")
		(4 "In1.Cu" signal "GND")
		(6 "In2.Cu" signal "VCC")
		(8 "In3.Cu" signal "VCC1")
		(10 "In4.Cu" signal "GND1")
		(12 "In5.Cu" signal "IN1")
		(14 "In6.Cu" signal "GND2")
		(16 "In7.Cu" signal "IN2")
		(18 "In8.Cu" signal "GND3")
		(20 "In9.Cu" signal "IN3")
		(22 "In10.Cu" signal "GND4")
		(24 "In11.Cu" signal "IN4")
		(26 "In12.Cu" signal "GND5")
		(28 "In13.Cu" signal "IN5")
		(30 "In14.Cu" signal "GND6")
		(32 "In15.Cu" signal "IN6")
		(34 "In16.Cu" signal "GND7")
		(2 "B.Cu" signal "BOTTOM")
		(9 "F.Adhes" user "F.Adhesive")
		(11 "B.Adhes" user "B.Adhesive")
		(13 "F.Paste" user "Package Geometry/Pastemask Top")
		(15 "B.Paste" user "Package Geometry/Pastemask Bottom")
		(5 "F.SilkS" user "Ref Des/Silkscreen Top")
		(7 "B.SilkS" user "Ref Des/Silkscreen Bottom")
		(1 "F.Mask" user "Board Geometry/Soldermask Top")
		(3 "B.Mask" user "Board Geometry/Soldermask Bottom")
		(17 "Dwgs.User" user "User.Drawings")
		(19 "Cmts.User" user "User.Comments")
		(21 "Eco1.User" user "User.Eco1")
		(23 "Eco2.User" user "User.Eco2")
		(25 "Edge.Cuts" user "Board Geometry/Outline")
		(27 "Margin" user)
		(31 "F.CrtYd" user "Package Geometry/Place Bound Top")
		(29 "B.CrtYd" user "Package Geometry/Place Bound Bottom")
		(35 "F.Fab" user "Ref Des/Assembly Top")
		(33 "B.Fab" user "Ref Des/Assembly Bottom")
	)
	(footprint ""
		(layer "B.Cu")
		(at 397.49984 -291.624766)
		(property "Reference" "C1870"
			(at 0 0 0)
			(layer "B.SilkS")
			(hide yes)
			(effects
				(font
					(size 1.27 1.27)
				)
				(justify mirror)
			)
		)
		(property "Value" ""
			(at 0 0 0)
			(layer "B.Fab")
			(effects
				(font
					(size 1.27 1.27)
				)
				(justify mirror)
			)
		)
		(duplicate_pad_numbers_are_jumpers no)
		(fp_line
			(start -0.299974 -0.150114)
			(end -0.299974 0.150114)
			(stroke
				(width 0.1)
				(type default)
			)
			(layer "B.Fab")
		)
		(fp_line
			(start -0.299974 0.150114)
			(end 0.299974 0.150114)
			(stroke
				(width 0.1)
				(type default)
			)
			(layer "B.Fab")
		)
		(fp_line
			(start 0.299974 -0.150114)
			(end -0.299974 -0.150114)
			(stroke
				(width 0.1)
				(type default)
			)
			(layer "B.Fab")
		)
		(fp_line
			(start 0.299974 0.150114)
			(end 0.299974 -0.150114)
			(stroke
				(width 0.1)
				(type default)
			)
			(layer "B.Fab")
		)
		(pad "1" smd rect
			(at 0.2667 0 180)
			(size 0.3048 0.381)
			(layers "B.Cu" "B.Mask" "B.Paste")
			(net "P0V8_PEX3")
		)
		(pad "2" smd rect
			(at -0.2667 0 180)
			(size 0.3048 0.381)
			(layers "B.Cu" "B.Mask" "B.Paste")
			(net "GND")
		)
	)
	(footprint ""
		(layer "B.Cu")
		(at 412.699962 -292.099746 90)
		(property "Reference" "C1991"
			(at 0 0 90)
			(layer "B.SilkS")
			(hide yes)
			(effects
				(font
					(size 1.27 1.27)
				)
				(justify mirror)
			)
		)
		(property "Value" ""
			(at 0 0 90)
			(layer "B.Fab")
			(effects
				(font
					(size 1.27 1.27)
				)
				(justify mirror)
			)
		)
		(duplicate_pad_numbers_are_jumpers no)
		(fp_line
			(start 0.299974 -0.150114)
			(end -0.299974 -0.150114)
			(stroke
				(width 0.1)
				(type default)
			)
			(layer "B.Fab")
		)
		(fp_line
			(start -0.299974 -0.150114)
			(end -0.299974 0.150114)
			(stroke
				(width 0.1)
				(type default)
			)
			(layer "B.Fab")
		)
		(fp_line
			(start 0.299974 0.150114)
			(end 0.299974 -0.150114)
			(stroke
				(width 0.1)
				(type default)
			)
			(layer "B.Fab")
		)
		(fp_line
			(start -0.299974 0.150114)
			(end 0.299974 0.150114)
			(stroke
				(width 0.1)
				(type default)
			)
			(layer "B.Fab")
		)
		(pad "1" smd rect
			(at 0.2667 0 270)
			(size 0.3048 0.381)
			(layers "B.Cu" "B.Mask" "B.Paste")
			(net "P0V8_SERDES_VDDA_PEX3")
		)
		(pad "2" smd rect
			(at -0.2667 0 270)
			(size 0.3048 0.381)
			(layers "B.Cu" "B.Mask" "B.Paste")
			(net "GND")
		)
	)
	(footprint ""
		(layer "B.Cu")
		(at 400.349974 -301.599854 -90)
		(property "Reference" "C1932"
			(at 0 0 90)
			(layer "B.SilkS")
			(hide yes)
			(effects
				(font
					(size 1.27 1.27)
				)
				(justify mirror)
			)
		)
		(property "Value" ""
			(at 0 0 90)
			(layer "B.Fab")
			(effects
				(font
					(size 1.27 1.27)
				)
				(justify mirror)
			)
		)
		(duplicate_pad_numbers_are_jumpers no)
		(fp_line
			(start -0.299974 0.150114)
			(end 0.299974 0.150114)
			(stroke
				(width 0.1)
				(type default)
			)
			(layer "B.Fab")
		)
		(fp_line
			(start 0.299974 0.150114)
			(end 0.299974 -0.150114)
			(stroke
				(width 0.1)
				(type default)
			)
			(layer "B.Fab")
		)
		(fp_line
			(start -0.299974 -0.150114)
			(end -0.299974 0.150114)
			(stroke
				(width 0.1)
				(type default)
			)
			(layer "B.Fab")
		)
		(fp_line
			(start 0.299974 -0.150114)
			(end -0.299974 -0.150114)
			(stroke
				(width 0.1)
				(type default)
			)
			(layer "B.Fab")
		)
		(pad "1" smd rect
			(at 0.2667 0 90)
			(size 0.3048 0.381)
			(layers "B.Cu" "B.Mask" "B.Paste")
			(net "P0V8_SERDES_VDDA_PEX3")
		)
		(pad "2" smd rect
			(at -0.2667 0 90)
			(size 0.3048 0.381)
			(layers "B.Cu" "B.Mask" "B.Paste")
			(net "GND")
		)
	)
	(footprint ""
		(layer "B.Cu")
		(at 337.488022 -319.545462 -90)
		(property "Reference" "L64"
			(at 0 0 90)
			(layer "B.SilkS")
			(hide yes)
			(effects
				(font
					(size 1.27 1.27)
				)
				(justify mirror)
			)
		)
		(property "Value" ""
			(at 0 0 90)
			(layer "B.Fab")
			(effects
				(font
					(size 1.27 1.27)
				)
				(justify mirror)
			)
		)
		(duplicate_pad_numbers_are_jumpers no)
		(fp_line
			(start -2.248154 4.9911)
			(end -2.248154 1.980692)
			(stroke
				(width 0.1524)
				(type default)
			)
			(layer "B.SilkS")
		)
		(fp_line
			(start 2.248154 4.9911)
			(end -2.248154 4.9911)
			(stroke
				(width 0.1524)
				(type default)
			)
			(layer "B.SilkS")
		)
		(fp_line
			(start 2.248154 1.980692)
			(end 2.248154 4.9911)
			(stroke
				(width 0.1524)
				(type default)
			)
			(layer "B.SilkS")
		)
		(fp_line
			(start -2.248154 -2.210816)
			(end -2.248154 -4.9911)
			(stroke
				(width 0.1524)
				(type default)
			)
			(layer "B.SilkS")
		)
		(fp_line
			(start -2.248154 -4.9911)
			(end 2.248154 -4.9911)
			(stroke
				(width 0.1524)
				(type default)
			)
			(layer "B.SilkS")
		)
		(fp_line
			(start 2.248154 -4.9911)
			(end 2.248154 -2.210816)
			(stroke
				(width 0.1524)
				(type default)
			)
			(layer "B.SilkS")
		)
		(fp_line
			(start -1.700022 0.899922)
			(end -1.700022 -0.899922)
			(stroke
				(width 0.1)
				(type default)
			)
			(layer "B.Fab")
		)
		(fp_line
			(start 1.700022 0.899922)
			(end -1.700022 0.899922)
			(stroke
				(width 0.1)
				(type default)
			)
			(layer "B.Fab")
		)
		(fp_line
			(start -1.700022 -0.899922)
			(end 1.700022 -0.899922)
			(stroke
				(width 0.1)
				(type default)
			)
			(layer "B.Fab")
		)
		(fp_line
			(start 1.700022 -0.899922)
			(end 1.700022 0.899922)
			(stroke
				(width 0.1)
				(type default)
			)
			(layer "B.Fab")
		)
		(pad "1" smd rect
			(at 1.575054 0 90)
			(size 1.1684 9.8044)
			(layers "B.Cu" "B.Mask" "B.Paste")
			(net "P0V8_PEX2")
		)
		(pad "2" smd rect
			(at -1.575054 0 90)
			(size 1.1684 9.8044)
			(layers "B.Cu" "B.Mask" "B.Paste")
			(net "P0V8_SERDES_VDDA_PEX2")
		)
	)
	(footprint ""
		(layer "B.Cu")
		(at 260.456426 -237.190788)
		(property "Reference" "C4427"
			(at 0 0 0)
			(layer "B.SilkS")
			(hide yes)
			(effects
				(font
					(size 1.27 1.27)
				)
				(justify mirror)
			)
		)
		(property "Value" ""
			(at 0 0 0)
			(layer "B.Fab")
			(effects
				(font
					(size 1.27 1.27)
				)
				(justify mirror)
			)
		)
		(duplicate_pad_numbers_are_jumpers no)
		(fp_line
			(start -0.7874 -0.4064)
			(end -0.7874 0.4064)
			(stroke
				(width 0.1524)
				(type default)
			)
			(layer "B.SilkS")
		)
		(fp_line
			(start -0.7874 0.4064)
			(end 0.7874 0.4064)
			(stroke
				(width 0.1524)
				(type default)
			)
			(layer "B.SilkS")
		)
		(fp_line
			(start 0.7874 -0.4064)
			(end -0.7874 -0.4064)
			(stroke
				(width 0.1524)
				(type default)
			)
			(layer "B.SilkS")
		)
		(fp_line
			(start 0.7874 0.4064)
			(end 0.7874 -0.4064)
			(stroke
				(width 0.1524)
				(type default)
			)
			(layer "B.SilkS")
		)
		(fp_line
			(start -0.67945 -0.3048)
			(end -0.67945 0.3048)
			(stroke
				(width 0.1)
				(type default)
			)
			(layer "B.Fab")
		)
		(fp_line
			(start -0.67945 0.3048)
			(end -0.120396 0.3048)
			(stroke
				(width 0.1)
				(type default)
			)
			(layer "B.Fab")
		)
		(fp_line
			(start -0.12065 -0.3048)
			(end -0.67945 -0.3048)
			(stroke
				(width 0.1)
				(type default)
			)
			(layer "B.Fab")
		)
		(fp_line
			(start -0.12065 -0.2794)
			(end -0.12065 -0.3048)
			(stroke
				(width 0.1)
				(type default)
			)
			(layer "B.Fab")
		)
		(fp_line
			(start -0.120396 0.2794)
			(end 0.12065 0.2794)
			(stroke
				(width 0.1)
				(type default)
			)
			(layer "B.Fab")
		)
		(fp_line
			(start -0.120396 0.3048)
			(end -0.120396 0.2794)
			(stroke
				(width 0.1)
				(type default)
			)
			(layer "B.Fab")
		)
		(fp_line
			(start 0.12065 -0.305054)
			(end 0.12065 -0.2794)
			(stroke
				(width 0.1)
				(type default)
			)
			(layer "B.Fab")
		)
		(fp_line
			(start 0.12065 -0.2794)
			(end -0.12065 -0.2794)
			(stroke
				(width 0.1)
				(type default)
			)
			(layer "B.Fab")
		)
		(fp_line
			(start 0.12065 0.2794)
			(end 0.12065 0.3048)
			(stroke
				(width 0.1)
				(type default)
			)
			(layer "B.Fab")
		)
		(fp_line
			(start 0.12065 0.3048)
			(end 0.67945 0.3048)
			(stroke
				(width 0.1)
				(type default)
			)
			(layer "B.Fab")
		)
		(fp_line
			(start 0.67945 -0.305054)
			(end 0.12065 -0.305054)
			(stroke
				(width 0.1)
				(type default)
			)
			(layer "B.Fab")
		)
		(fp_line
			(start 0.67945 0.3048)
			(end 0.67945 -0.305054)
			(stroke
				(width 0.1)
				(type default)
			)
			(layer "B.Fab")
		)
		(pad "1" smd circle
			(at 0.40005 0 180)
			(size 0 0)
			(layers "B.Cu" "B.Mask" "B.Paste")
			(net "P1V8_PLL0_PEX2")
		)
		(pad "2" smd circle
			(at -0.40005 0 180)
			(size 0 0)
			(layers "B.Cu" "B.Mask" "B.Paste")
			(net "GND")
		)
	)
	(footprint ""
		(layer "B.Cu")
		(at 244.901212 -291.888926 180)
		(property "Reference" "PC995"
			(at 0 0 0)
			(layer "B.SilkS")
			(hide yes)
			(effects
				(font
					(size 1.27 1.27)
				)
				(justify mirror)
			)
		)
		(property "Value" ""
			(at 0 0 0)
			(layer "B.Fab")
			(effects
				(font
					(size 1.27 1.27)
				)
				(justify mirror)
			)
		)
		(duplicate_pad_numbers_are_jumpers no)
		(fp_line
			(start 1.524 0.762)
			(end 1.524 -0.762)
			(stroke
				(width 0.1524)
				(type default)
			)
			(layer "B.SilkS")
		)
		(fp_line
			(start 1.524 -0.762)
			(end -1.524 -0.762)
			(stroke
				(width 0.1524)
				(type default)
			)
			(layer "B.SilkS")
		)
		(fp_line
			(start -1.524 0.762)
			(end 1.524 0.762)
			(stroke
				(width 0.1524)
				(type default)
			)
			(layer "B.SilkS")
		)
		(fp_line
			(start -1.524 -0.762)
			(end -1.524 0.762)
			(stroke
				(width 0.1524)
				(type default)
			)
			(layer "B.SilkS")
		)
		(fp_line
			(start 1.1049 0.724916)
			(end -1.1049 0.724916)
			(stroke
				(width 0.1)
				(type default)
			)
			(layer "B.Fab")
		)
		(fp_line
			(start 1.1049 -0.724916)
			(end 1.1049 0.724916)
			(stroke
				(width 0.1)
				(type default)
			)
			(layer "B.Fab")
		)
		(fp_line
			(start -1.1049 0.724916)
			(end -1.1049 -0.724916)
			(stroke
				(width 0.1)
				(type default)
			)
			(layer "B.Fab")
		)
		(fp_line
			(start -1.1049 -0.724916)
			(end 1.1049 -0.724916)
			(stroke
				(width 0.1)
				(type default)
			)
			(layer "B.Fab")
		)
		(pad "1" smd rect
			(at 0.889 0 180)
			(size 1.016 1.27)
			(layers "B.Cu" "B.Mask" "B.Paste")
			(net "P1V25_PEX2_R")
		)
		(pad "2" smd rect
			(at -0.889 0 180)
			(size 1.016 1.27)
			(layers "B.Cu" "B.Mask" "B.Paste")
			(net "GND")
		)
	)
	(footprint ""
		(layer "B.Cu")
		(at 397.49984 -299.2755 180)
		(property "Reference" "C1893"
			(at 0 0 0)
			(layer "B.SilkS")
			(hide yes)
			(effects
				(font
					(size 1.27 1.27)
				)
				(justify mirror)
			)
		)
		(property "Value" ""
			(at 0 0 0)
			(layer "B.Fab")
			(effects
				(font
					(size 1.27 1.27)
				)
				(justify mirror)
			)
		)
		(duplicate_pad_numbers_are_jumpers no)
		(fp_line
			(start 0.299974 0.150114)
			(end 0.299974 -0.150114)
			(stroke
				(width 0.1)
				(type default)
			)
			(layer "B.Fab")
		)
		(fp_line
			(start 0.299974 -0.150114)
			(end -0.299974 -0.150114)
			(stroke
				(width 0.1)
				(type default)
			)
			(layer "B.Fab")
		)
		(fp_line
			(start -0.299974 0.150114)
			(end 0.299974 0.150114)
			(stroke
				(width 0.1)
				(type default)
			)
			(layer "B.Fab")
		)
		(fp_line
			(start -0.299974 -0.150114)
			(end -0.299974 0.150114)
			(stroke
				(width 0.1)
				(type default)
			)
			(layer "B.Fab")
		)
		(pad "1" smd rect
			(at 0.2667 0)
			(size 0.3048 0.381)
			(layers "B.Cu" "B.Mask" "B.Paste")
			(net "P0V8_PEX3")
		)
		(pad "2" smd rect
			(at -0.2667 0)
			(size 0.3048 0.381)
			(layers "B.Cu" "B.Mask" "B.Paste")
			(net "GND")
		)
	)
	(footprint ""
		(layer "B.Cu")
		(at 227.067618 -218.30411 180)
		(property "Reference" "C2013"
			(at 0 0 0)
			(layer "B.SilkS")
			(hide yes)
			(effects
				(font
					(size 1.27 1.27)
				)
				(justify mirror)
			)
		)
		(property "Value" ""
			(at 0 0 0)
			(layer "B.Fab")
			(effects
				(font
					(size 1.27 1.27)
				)
				(justify mirror)
			)
		)
		(duplicate_pad_numbers_are_jumpers no)
		(fp_line
			(start 0.69215 0.2921)
			(end 0.69215 -0.2921)
			(stroke
				(width 0.1524)
				(type default)
			)
			(layer "B.SilkS")
		)
		(fp_line
			(start 0.69215 -0.2921)
			(end -0.69215 -0.2921)
			(stroke
				(width 0.1524)
				(type default)
			)
			(layer "B.SilkS")
		)
		(fp_line
			(start -0.69215 0.2921)
			(end 0.69215 0.2921)
			(stroke
				(width 0.1524)
				(type default)
			)
			(layer "B.SilkS")
		)
		(fp_line
			(start -0.69215 -0.2921)
			(end -0.69215 0.2921)
			(stroke
				(width 0.1524)
				(type default)
			)
			(layer "B.SilkS")
		)
		(fp_line
			(start 0.51435 0.2794)
			(end 0.51435 -0.2794)
			(stroke
				(width 0.1)
				(type default)
			)
			(layer "B.Fab")
		)
		(fp_line
			(start 0.51435 -0.2794)
			(end -0.51435 -0.2794)
			(stroke
				(width 0.1)
				(type default)
			)
			(layer "B.Fab")
		)
		(fp_line
			(start -0.51435 0.2794)
			(end 0.51435 0.2794)
			(stroke
				(width 0.1)
				(type default)
			)
			(layer "B.Fab")
		)
		(fp_line
			(start -0.51435 -0.2794)
			(end -0.51435 0.2794)
			(stroke
				(width 0.1)
				(type default)
			)
			(layer "B.Fab")
		)
		(pad "1" smd circle
			(at 0.40005 0)
			(size 0 0)
			(layers "B.Cu" "B.Mask" "B.Paste")
			(net "P1V2_AUX")
		)
		(pad "2" smd circle
			(at -0.40005 0)
			(size 0 0)
			(layers "B.Cu" "B.Mask" "B.Paste")
			(net "GND")
		)
		(zone
			(layer "B.Cu")
			(hatch none 0.5)
			(connect_pads
				(clearance 0)
			)
			(min_thickness 0.25)
			(keepout
				(tracks not_allowed)
				(vias allowed)
				(pads allowed)
				(copperpour not_allowed)
				(footprints allowed)
			)
			(placement
				(enabled no)
				(sheetname "")
			)
			(fill
				(thermal_gap 0.5)
				(thermal_bridge_width 0.5)
				(island_removal_mode 0)
			)
			(polygon
				(pts
					(xy 226.877118 -218.39174) (xy 226.968558 -218.449906) (xy 227.167948 -218.449906) (xy 227.258118 -218.39174)
					(xy 227.258118 -218.21648) (xy 227.167948 -218.15806) (xy 226.968558 -218.15806) (xy 226.877118 -218.216226)
				)
			)
		)
	)
	(footprint ""
		(layer "B.Cu")
		(at 399.400014 -288.299906 90)
		(property "Reference" "C3456"
			(at 0 0 90)
			(layer "B.SilkS")
			(hide yes)
			(effects
				(font
					(size 1.27 1.27)
				)
				(justify mirror)
			)
		)
		(property "Value" ""
			(at 0 0 90)
			(layer "B.Fab")
			(effects
				(font
					(size 1.27 1.27)
				)
				(justify mirror)
			)
		)
		(duplicate_pad_numbers_are_jumpers no)
		(fp_line
			(start 0.299974 -0.150114)
			(end -0.299974 -0.150114)
			(stroke
				(width 0.1)
				(type default)
			)
			(layer "B.Fab")
		)
		(fp_line
			(start -0.299974 -0.150114)
			(end -0.299974 0.150114)
			(stroke
				(width 0.1)
				(type default)
			)
			(layer "B.Fab")
		)
		(fp_line
			(start 0.299974 0.150114)
			(end 0.299974 -0.150114)
			(stroke
				(width 0.1)
				(type default)
			)
			(layer "B.Fab")
		)
		(fp_line
			(start -0.299974 0.150114)
			(end 0.299974 0.150114)
			(stroke
				(width 0.1)
				(type default)
			)
			(layer "B.Fab")
		)
		(pad "1" smd rect
			(at 0.2667 0 270)
			(size 0.3048 0.381)
			(layers "B.Cu" "B.Mask" "B.Paste")
			(net "P1V25_PEX3")
		)
		(pad "2" smd rect
			(at -0.2667 0 270)
			(size 0.3048 0.381)
			(layers "B.Cu" "B.Mask" "B.Paste")
			(net "GND")
		)
	)
	(footprint ""
		(layer "B.Cu")
		(at 116.935758 -260.400546 -90)
		(property "Reference" "PC55"
			(at 0 0 90)
			(layer "B.SilkS")
			(hide yes)
			(effects
				(font
					(size 1.27 1.27)
				)
				(justify mirror)
			)
		)
		(property "Value" ""
			(at 0 0 90)
			(layer "B.Fab")
			(effects
				(font
					(size 1.27 1.27)
				)
				(justify mirror)
			)
		)
		(duplicate_pad_numbers_are_jumpers no)
		(fp_line
			(start -0.7874 0.4064)
			(end 0.7874 0.4064)
			(stroke
				(width 0.1524)
				(type default)
			)
			(layer "B.SilkS")
		)
		(fp_line
			(start 0.7874 0.4064)
			(end 0.7874 -0.4064)
			(stroke
				(width 0.1524)
				(type default)
			)
			(layer "B.SilkS")
		)
		(fp_line
			(start -0.7874 -0.4064)
			(end -0.7874 0.4064)
			(stroke
				(width 0.1524)
				(type default)
			)
			(layer "B.SilkS")
		)
		(fp_line
			(start 0.7874 -0.4064)
			(end -0.7874 -0.4064)
			(stroke
				(width 0.1524)
				(type default)
			)
			(layer "B.SilkS")
		)
		(fp_line
			(start -0.67945 0.3048)
			(end -0.120396 0.3048)
			(stroke
				(width 0.1)
				(type default)
			)
			(layer "B.Fab")
		)
		(fp_line
			(start -0.120396 0.3048)
			(end -0.120396 0.2794)
			(stroke
				(width 0.1)
				(type default)
			)
			(layer "B.Fab")
		)
		(fp_line
			(start 0.12065 0.3048)
			(end 0.67945 0.3048)
			(stroke
				(width 0.1)
				(type default)
			)
			(layer "B.Fab")
		)
		(fp_line
			(start 0.67945 0.3048)
			(end 0.67945 -0.305054)
			(stroke
				(width 0.1)
				(type default)
			)
			(layer "B.Fab")
		)
		(fp_line
			(start -0.120396 0.2794)
			(end 0.12065 0.2794)
			(stroke
				(width 0.1)
				(type default)
			)
			(layer "B.Fab")
		)
		(fp_line
			(start 0.12065 0.2794)
			(end 0.12065 0.3048)
			(stroke
				(width 0.1)
				(type default)
			)
			(layer "B.Fab")
		)
		(fp_line
			(start -0.12065 -0.2794)
			(end -0.12065 -0.3048)
			(stroke
				(width 0.1)
				(type default)
			)
			(layer "B.Fab")
		)
		(fp_line
			(start 0.12065 -0.2794)
			(end -0.12065 -0.2794)
			(stroke
				(width 0.1)
				(type default)
			)
			(layer "B.Fab")
		)
		(fp_line
			(start -0.67945 -0.3048)
			(end -0.67945 0.3048)
			(stroke
				(width 0.1)
				(type default)
			)
			(layer "B.Fab")
		)
		(fp_line
			(start -0.12065 -0.3048)
			(end -0.67945 -0.3048)
			(stroke
				(width 0.1)
				(type default)
			)
			(layer "B.Fab")
		)
		(fp_line
			(start 0.12065 -0.305054)
			(end 0.12065 -0.2794)
			(stroke
				(width 0.1)
				(type default)
			)
			(layer "B.Fab")
		)
		(fp_line
			(start 0.67945 -0.305054)
			(end 0.12065 -0.305054)
			(stroke
				(width 0.1)
				(type default)
			)
			(layer "B.Fab")
		)
		(pad "1" smd circle
			(at 0.40005 0 90)
			(size 0 0)
			(layers "B.Cu" "B.Mask" "B.Paste")
			(net "P0V8_PEX0_TSEN_R")
		)
		(pad "2" smd circle
			(at -0.40005 0 90)
			(size 0 0)
			(layers "B.Cu" "B.Mask" "B.Paste")
			(net "GND")
		)
	)
)
